(kicad_pcb
	(version 20260206)
	(generator "pcbnew")
	(generator_version "10.0")
	(general
		(thickness 1.6)
		(legacy_teardrops no)
	)
	(paper "A4")
	(title_block
		(title "12092022_DA0F0TMDCD0_F0T_Management_Board_D_brd_V3_OCP.brd")
		(comment 1 "Grand Teton / footprints 336-341 of 1440")
	)
	(layers
		(0 "F.Cu" signal "TOP")
		(4 "In1.Cu" signal "GND")
		(6 "In2.Cu" signal "IN1")
		(8 "In3.Cu" signal "GND1")
		(10 "In4.Cu" signal "IN2")
		(12 "In5.Cu" signal "VCC")
		(14 "In6.Cu" signal "VCC1")
		(16 "In7.Cu" signal "IN3")
		(18 "In8.Cu" signal "GND2")
		(20 "In9.Cu" signal "IN4")
		(22 "In10.Cu" signal "GND3")
		(2 "B.Cu" signal "BOTTOM")
		(9 "F.Adhes" user "F.Adhesive")
		(11 "B.Adhes" user "B.Adhesive")
		(13 "F.Paste" user "Package Geometry/Pastemask Top")
		(15 "B.Paste" user "Package Geometry/Pastemask Bottom")
		(5 "F.SilkS" user "Ref Des/Silkscreen Top")
		(7 "B.SilkS" user "Ref Des/Silkscreen Bottom")
		(1 "F.Mask" user "Board Geometry/Soldermask Top")
		(3 "B.Mask" user "Board Geometry/Soldermask Bottom")
		(17 "Dwgs.User" user "User.Drawings")
		(19 "Cmts.User" user "User.Comments")
		(21 "Eco1.User" user "User.Eco1")
		(23 "Eco2.User" user "User.Eco2")
		(25 "Edge.Cuts" user "Board Geometry/Outline")
		(27 "Margin" user)
		(31 "F.CrtYd" user "Package Geometry/Place Bound Top")
		(29 "B.CrtYd" user "Package Geometry/Place Bound Bottom")
		(35 "F.Fab" user "Ref Des/Assembly Top")
		(33 "B.Fab" user "Ref Des/Assembly Bottom")
	)
	(footprint ""
		(layer "F.Cu")
		(at 38.079172 -83.816952 90)
		(property "Reference" "R649"
			(at 0 0 90)
			(layer "F.SilkS")
			(hide yes)
			(effects
				(font
					(size 1.27 1.27)
				)
			)
		)
		(property "Value" ""
			(at 0 0 90)
			(layer "F.Fab")
			(effects
				(font
					(size 1.27 1.27)
				)
			)
		)
		(duplicate_pad_numbers_are_jumpers no)
		(fp_line
			(start 0.7874 -0.4064)
			(end 0.7874 0.4064)
			(stroke
				(width 0.1524)
				(type default)
			)
			(layer "F.SilkS")
		)
		(fp_line
			(start -0.7874 -0.4064)
			(end 0.7874 -0.4064)
			(stroke
				(width 0.1524)
				(type default)
			)
			(layer "F.SilkS")
		)
		(fp_line
			(start 0.7874 0.4064)
			(end -0.7874 0.4064)
			(stroke
				(width 0.1524)
				(type default)
			)
			(layer "F.SilkS")
		)
		(fp_line
			(start -0.7874 0.4064)
			(end -0.7874 -0.4064)
			(stroke
				(width 0.1524)
				(type default)
			)
			(layer "F.SilkS")
		)
		(fp_line
			(start -0.12065 -0.305054)
			(end -0.12065 -0.2794)
			(stroke
				(width 0.1)
				(type default)
			)
			(layer "F.Fab")
		)
		(fp_line
			(start -0.67945 -0.305054)
			(end -0.12065 -0.305054)
			(stroke
				(width 0.1)
				(type default)
			)
			(layer "F.Fab")
		)
		(fp_line
			(start 0.67945 -0.3048)
			(end 0.67945 0.3048)
			(stroke
				(width 0.1)
				(type default)
			)
			(layer "F.Fab")
		)
		(fp_line
			(start 0.12065 -0.3048)
			(end 0.67945 -0.3048)
			(stroke
				(width 0.1)
				(type default)
			)
			(layer "F.Fab")
		)
		(fp_line
			(start 0.12065 -0.2794)
			(end 0.12065 -0.3048)
			(stroke
				(width 0.1)
				(type default)
			)
			(layer "F.Fab")
		)
		(fp_line
			(start -0.12065 -0.2794)
			(end 0.12065 -0.2794)
			(stroke
				(width 0.1)
				(type default)
			)
			(layer "F.Fab")
		)
		(fp_line
			(start 0.120396 0.2794)
			(end -0.12065 0.2794)
			(stroke
				(width 0.1)
				(type default)
			)
			(layer "F.Fab")
		)
		(fp_line
			(start -0.12065 0.2794)
			(end -0.12065 0.3048)
			(stroke
				(width 0.1)
				(type default)
			)
			(layer "F.Fab")
		)
		(fp_line
			(start 0.67945 0.3048)
			(end 0.120396 0.3048)
			(stroke
				(width 0.1)
				(type default)
			)
			(layer "F.Fab")
		)
		(fp_line
			(start 0.120396 0.3048)
			(end 0.120396 0.2794)
			(stroke
				(width 0.1)
				(type default)
			)
			(layer "F.Fab")
		)
		(fp_line
			(start -0.12065 0.3048)
			(end -0.67945 0.3048)
			(stroke
				(width 0.1)
				(type default)
			)
			(layer "F.Fab")
		)
		(fp_line
			(start -0.67945 0.3048)
			(end -0.67945 -0.305054)
			(stroke
				(width 0.1)
				(type default)
			)
			(layer "F.Fab")
		)
		(pad "1" smd circle
			(at -0.40005 0 90)
			(size 0 0)
			(layers "F.Cu" "F.Mask" "F.Paste")
			(net "EMMC_DT0_R")
		)
		(pad "2" smd circle
			(at 0.40005 0 90)
			(size 0 0)
			(layers "F.Cu" "F.Mask" "F.Paste")
			(net "BMC_EMMC_DT0")
		)
	)
	(footprint ""
		(layer "F.Cu")
		(at 85.471 -34.544 -90)
		(property "Reference" "C289"
			(at 0 0 270)
			(layer "F.SilkS")
			(hide yes)
			(effects
				(font
					(size 1.27 1.27)
				)
			)
		)
		(property "Value" ""
			(at 0 0 270)
			(layer "F.Fab")
			(effects
				(font
					(size 1.27 1.27)
				)
			)
		)
		(duplicate_pad_numbers_are_jumpers no)
		(fp_line
			(start -1.651 0.8382)
			(end -1.651 -0.8382)
			(stroke
				(width 0.1524)
				(type default)
			)
			(layer "F.SilkS")
		)
		(fp_line
			(start 0 0.8382)
			(end 0 -0.8382)
			(stroke
				(width 0.1524)
				(type default)
			)
			(layer "F.SilkS")
		)
		(fp_line
			(start 1.651 0.8382)
			(end -1.651 0.8382)
			(stroke
				(width 0.1524)
				(type default)
			)
			(layer "F.SilkS")
		)
		(fp_line
			(start -1.651 -0.8382)
			(end 1.651 -0.8382)
			(stroke
				(width 0.1524)
				(type default)
			)
			(layer "F.SilkS")
		)
		(fp_line
			(start 1.651 -0.8382)
			(end 1.651 0.8382)
			(stroke
				(width 0.1524)
				(type default)
			)
			(layer "F.SilkS")
		)
		(fp_line
			(start -1.55956 0.7366)
			(end -1.524 0.7366)
			(stroke
				(width 0.1)
				(type default)
			)
			(layer "F.Fab")
		)
		(fp_line
			(start -1.524 0.7366)
			(end 1.524 0.7366)
			(stroke
				(width 0.1)
				(type default)
			)
			(layer "F.Fab")
		)
		(fp_line
			(start 1.524 0.7366)
			(end 1.55956 0.7366)
			(stroke
				(width 0.1)
				(type default)
			)
			(layer "F.Fab")
		)
		(fp_line
			(start 1.55956 0.7366)
			(end 1.55956 -0.7366)
			(stroke
				(width 0.1)
				(type default)
			)
			(layer "F.Fab")
		)
		(fp_line
			(start -1.55956 -0.7366)
			(end -1.55956 0.7366)
			(stroke
				(width 0.1)
				(type default)
			)
			(layer "F.Fab")
		)
		(fp_line
			(start -1.524 -0.7366)
			(end -1.55956 -0.7366)
			(stroke
				(width 0.1)
				(type default)
			)
			(layer "F.Fab")
		)
		(fp_line
			(start 1.524 -0.7366)
			(end -1.524 -0.7366)
			(stroke
				(width 0.1)
				(type default)
			)
			(layer "F.Fab")
		)
		(fp_line
			(start 1.55956 -0.7366)
			(end 1.524 -0.7366)
			(stroke
				(width 0.1)
				(type default)
			)
			(layer "F.Fab")
		)
		(pad "1" smd rect
			(at -0.94996 0 90)
			(size 1.1176 1.3716)
			(layers "F.Cu" "F.Mask" "F.Paste")
			(net "P2V5_AUX")
		)
		(pad "2" smd rect
			(at 0.94996 0 90)
			(size 1.1176 1.3716)
			(layers "F.Cu" "F.Mask" "F.Paste")
			(net "GND")
		)
	)
	(footprint ""
		(layer "F.Cu")
		(at 57.222136 -34.637726 -90)
		(property "Reference" "R584"
			(at 0 0 270)
			(layer "F.SilkS")
			(hide yes)
			(effects
				(font
					(size 1.27 1.27)
				)
			)
		)
		(property "Value" ""
			(at 0 0 270)
			(layer "F.Fab")
			(effects
				(font
					(size 1.27 1.27)
				)
			)
		)
		(duplicate_pad_numbers_are_jumpers no)
		(fp_line
			(start -0.7874 0.4064)
			(end -0.7874 -0.4064)
			(stroke
				(width 0.1524)
				(type default)
			)
			(layer "F.SilkS")
		)
		(fp_line
			(start 0.7874 0.4064)
			(end -0.7874 0.4064)
			(stroke
				(width 0.1524)
				(type default)
			)
			(layer "F.SilkS")
		)
		(fp_line
			(start -0.7874 -0.4064)
			(end 0.7874 -0.4064)
			(stroke
				(width 0.1524)
				(type default)
			)
			(layer "F.SilkS")
		)
		(fp_line
			(start 0.7874 -0.4064)
			(end 0.7874 0.4064)
			(stroke
				(width 0.1524)
				(type default)
			)
			(layer "F.SilkS")
		)
		(fp_line
			(start -0.67945 0.3048)
			(end -0.67945 -0.305054)
			(stroke
				(width 0.1)
				(type default)
			)
			(layer "F.Fab")
		)
		(fp_line
			(start -0.12065 0.3048)
			(end -0.67945 0.3048)
			(stroke
				(width 0.1)
				(type default)
			)
			(layer "F.Fab")
		)
		(fp_line
			(start 0.120396 0.3048)
			(end 0.120396 0.2794)
			(stroke
				(width 0.1)
				(type default)
			)
			(layer "F.Fab")
		)
		(fp_line
			(start 0.67945 0.3048)
			(end 0.120396 0.3048)
			(stroke
				(width 0.1)
				(type default)
			)
			(layer "F.Fab")
		)
		(fp_line
			(start -0.12065 0.2794)
			(end -0.12065 0.3048)
			(stroke
				(width 0.1)
				(type default)
			)
			(layer "F.Fab")
		)
		(fp_line
			(start 0.120396 0.2794)
			(end -0.12065 0.2794)
			(stroke
				(width 0.1)
				(type default)
			)
			(layer "F.Fab")
		)
		(fp_line
			(start -0.12065 -0.2794)
			(end 0.12065 -0.2794)
			(stroke
				(width 0.1)
				(type default)
			)
			(layer "F.Fab")
		)
		(fp_line
			(start 0.12065 -0.2794)
			(end 0.12065 -0.3048)
			(stroke
				(width 0.1)
				(type default)
			)
			(layer "F.Fab")
		)
		(fp_line
			(start 0.12065 -0.3048)
			(end 0.67945 -0.3048)
			(stroke
				(width 0.1)
				(type default)
			)
			(layer "F.Fab")
		)
		(fp_line
			(start 0.67945 -0.3048)
			(end 0.67945 0.3048)
			(stroke
				(width 0.1)
				(type default)
			)
			(layer "F.Fab")
		)
		(fp_line
			(start -0.67945 -0.305054)
			(end -0.12065 -0.305054)
			(stroke
				(width 0.1)
				(type default)
			)
			(layer "F.Fab")
		)
		(fp_line
			(start -0.12065 -0.305054)
			(end -0.12065 -0.2794)
			(stroke
				(width 0.1)
				(type default)
			)
			(layer "F.Fab")
		)
		(pad "1" smd circle
			(at -0.40005 0 270)
			(size 0 0)
			(layers "F.Cu" "F.Mask" "F.Paste")
			(net "SMB_BMC_MM10_R_SDA")
		)
		(pad "2" smd circle
			(at 0.40005 0 270)
			(size 0 0)
			(layers "F.Cu" "F.Mask" "F.Paste")
			(net "SMB_BMC_MM10_SDA")
		)
	)
	(footprint ""
		(layer "F.Cu")
		(at 35.1536 -89.3826 180)
		(property "Reference" "R486"
			(at 0 0 180)
			(layer "F.SilkS")
			(hide yes)
			(effects
				(font
					(size 1.27 1.27)
				)
			)
		)
		(property "Value" ""
			(at 0 0 180)
			(layer "F.Fab")
			(effects
				(font
					(size 1.27 1.27)
				)
			)
		)
		(duplicate_pad_numbers_are_jumpers no)
		(fp_line
			(start 0.7874 0.4064)
			(end -0.7874 0.4064)
			(stroke
				(width 0.1524)
				(type default)
			)
			(layer "F.SilkS")
		)
		(fp_line
			(start 0.7874 -0.4064)
			(end 0.7874 0.4064)
			(stroke
				(width 0.1524)
				(type default)
			)
			(layer "F.SilkS")
		)
		(fp_line
			(start -0.7874 0.4064)
			(end -0.7874 -0.4064)
			(stroke
				(width 0.1524)
				(type default)
			)
			(layer "F.SilkS")
		)
		(fp_line
			(start -0.7874 -0.4064)
			(end 0.7874 -0.4064)
			(stroke
				(width 0.1524)
				(type default)
			)
			(layer "F.SilkS")
		)
		(fp_line
			(start 0.67945 0.3048)
			(end 0.120396 0.3048)
			(stroke
				(width 0.1)
				(type default)
			)
			(layer "F.Fab")
		)
		(fp_line
			(start 0.67945 -0.3048)
			(end 0.67945 0.3048)
			(stroke
				(width 0.1)
				(type default)
			)
			(layer "F.Fab")
		)
		(fp_line
			(start 0.12065 -0.2794)
			(end 0.12065 -0.3048)
			(stroke
				(width 0.1)
				(type default)
			)
			(layer "F.Fab")
		)
		(fp_line
			(start 0.12065 -0.3048)
			(end 0.67945 -0.3048)
			(stroke
				(width 0.1)
				(type default)
			)
			(layer "F.Fab")
		)
		(fp_line
			(start 0.120396 0.3048)
			(end 0.120396 0.2794)
			(stroke
				(width 0.1)
				(type default)
			)
			(layer "F.Fab")
		)
		(fp_line
			(start 0.120396 0.2794)
			(end -0.12065 0.2794)
			(stroke
				(width 0.1)
				(type default)
			)
			(layer "F.Fab")
		)
		(fp_line
			(start -0.12065 0.3048)
			(end -0.67945 0.3048)
			(stroke
				(width 0.1)
				(type default)
			)
			(layer "F.Fab")
		)
		(fp_line
			(start -0.12065 0.2794)
			(end -0.12065 0.3048)
			(stroke
				(width 0.1)
				(type default)
			)
			(layer "F.Fab")
		)
		(fp_line
			(start -0.12065 -0.2794)
			(end 0.12065 -0.2794)
			(stroke
				(width 0.1)
				(type default)
			)
			(layer "F.Fab")
		)
		(fp_line
			(start -0.12065 -0.305054)
			(end -0.12065 -0.2794)
			(stroke
				(width 0.1)
				(type default)
			)
			(layer "F.Fab")
		)
		(fp_line
			(start -0.67945 0.3048)
			(end -0.67945 -0.305054)
			(stroke
				(width 0.1)
				(type default)
			)
			(layer "F.Fab")
		)
		(fp_line
			(start -0.67945 -0.305054)
			(end -0.12065 -0.305054)
			(stroke
				(width 0.1)
				(type default)
			)
			(layer "F.Fab")
		)
		(pad "1" smd circle
			(at -0.40005 0 180)
			(size 0 0)
			(layers "F.Cu" "F.Mask" "F.Paste")
			(net "SPI_PCH_MUXED_IO3")
		)
		(pad "2" smd circle
			(at 0.40005 0 180)
			(size 0 0)
			(layers "F.Cu" "F.Mask" "F.Paste")
			(net "SPI_PCH_IO3_FLASH_R1")
		)
	)
	(footprint ""
		(layer "F.Cu")
		(at 30.5562 -87.9856 180)
		(property "Reference" "R81"
			(at 0 0 180)
			(layer "F.SilkS")
			(hide yes)
			(effects
				(font
					(size 1.27 1.27)
				)
			)
		)
		(property "Value" ""
			(at 0 0 180)
			(layer "F.Fab")
			(effects
				(font
					(size 1.27 1.27)
				)
			)
		)
		(duplicate_pad_numbers_are_jumpers no)
		(fp_line
			(start 0.7874 0.4064)
			(end -0.7874 0.4064)
			(stroke
				(width 0.1524)
				(type default)
			)
			(layer "F.SilkS")
		)
		(fp_line
			(start 0.7874 -0.4064)
			(end 0.7874 0.4064)
			(stroke
				(width 0.1524)
				(type default)
			)
			(layer "F.SilkS")
		)
		(fp_line
			(start -0.7874 0.4064)
			(end -0.7874 -0.4064)
			(stroke
				(width 0.1524)
				(type default)
			)
			(layer "F.SilkS")
		)
		(fp_line
			(start -0.7874 -0.4064)
			(end 0.7874 -0.4064)
			(stroke
				(width 0.1524)
				(type default)
			)
			(layer "F.SilkS")
		)
		(fp_line
			(start 0.67945 0.3048)
			(end 0.120396 0.3048)
			(stroke
				(width 0.1)
				(type default)
			)
			(layer "F.Fab")
		)
		(fp_line
			(start 0.67945 -0.3048)
			(end 0.67945 0.3048)
			(stroke
				(width 0.1)
				(type default)
			)
			(layer "F.Fab")
		)
		(fp_line
			(start 0.12065 -0.2794)
			(end 0.12065 -0.3048)
			(stroke
				(width 0.1)
				(type default)
			)
			(layer "F.Fab")
		)
		(fp_line
			(start 0.12065 -0.3048)
			(end 0.67945 -0.3048)
			(stroke
				(width 0.1)
				(type default)
			)
			(layer "F.Fab")
		)
		(fp_line
			(start 0.120396 0.3048)
			(end 0.120396 0.2794)
			(stroke
				(width 0.1)
				(type default)
			)
			(layer "F.Fab")
		)
		(fp_line
			(start 0.120396 0.2794)
			(end -0.12065 0.2794)
			(stroke
				(width 0.1)
				(type default)
			)
			(layer "F.Fab")
		)
		(fp_line
			(start -0.12065 0.3048)
			(end -0.67945 0.3048)
			(stroke
				(width 0.1)
				(type default)
			)
			(layer "F.Fab")
		)
		(fp_line
			(start -0.12065 0.2794)
			(end -0.12065 0.3048)
			(stroke
				(width 0.1)
				(type default)
			)
			(layer "F.Fab")
		)
		(fp_line
			(start -0.12065 -0.2794)
			(end 0.12065 -0.2794)
			(stroke
				(width 0.1)
				(type default)
			)
			(layer "F.Fab")
		)
		(fp_line
			(start -0.12065 -0.305054)
			(end -0.12065 -0.2794)
			(stroke
				(width 0.1)
				(type default)
			)
			(layer "F.Fab")
		)
		(fp_line
			(start -0.67945 0.3048)
			(end -0.67945 -0.305054)
			(stroke
				(width 0.1)
				(type default)
			)
			(layer "F.Fab")
		)
		(fp_line
			(start -0.67945 -0.305054)
			(end -0.12065 -0.305054)
			(stroke
				(width 0.1)
				(type default)
			)
			(layer "F.Fab")
		)
		(pad "1" smd circle
			(at -0.40005 0 180)
			(size 0 0)
			(layers "F.Cu" "F.Mask" "F.Paste")
			(net "P3V3_AUX")
		)
		(pad "2" smd circle
			(at 0.40005 0 180)
			(size 0 0)
			(layers "F.Cu" "F.Mask" "F.Paste")
			(net "PWR_BTN_BMC_N")
		)
	)
	(footprint ""
		(layer "F.Cu")
		(at 16.5354 -70.739 -90)
		(property "Reference" "R665"
			(at 0 0 270)
			(layer "F.SilkS")
			(hide yes)
			(effects
				(font
					(size 1.27 1.27)
				)
			)
		)
		(property "Value" ""
			(at 0 0 270)
			(layer "F.Fab")
			(effects
				(font
					(size 1.27 1.27)
				)
			)
		)
		(duplicate_pad_numbers_are_jumpers no)
		(fp_line
			(start -0.7874 0.4064)
			(end -0.7874 -0.4064)
			(stroke
				(width 0.1524)
				(type default)
			)
			(layer "F.SilkS")
		)
		(fp_line
			(start 0.7874 0.4064)
			(end -0.7874 0.4064)
			(stroke
				(width 0.1524)
				(type default)
			)
			(layer "F.SilkS")
		)
		(fp_line
			(start -0.7874 -0.4064)
			(end 0.7874 -0.4064)
			(stroke
				(width 0.1524)
				(type default)
			)
			(layer "F.SilkS")
		)
		(fp_line
			(start 0.7874 -0.4064)
			(end 0.7874 0.4064)
			(stroke
				(width 0.1524)
				(type default)
			)
			(layer "F.SilkS")
		)
		(fp_line
			(start -0.67945 0.3048)
			(end -0.67945 -0.305054)
			(stroke
				(width 0.1)
				(type default)
			)
			(layer "F.Fab")
		)
		(fp_line
			(start -0.12065 0.3048)
			(end -0.67945 0.3048)
			(stroke
				(width 0.1)
				(type default)
			)
			(layer "F.Fab")
		)
		(fp_line
			(start 0.120396 0.3048)
			(end 0.120396 0.2794)
			(stroke
				(width 0.1)
				(type default)
			)
			(layer "F.Fab")
		)
		(fp_line
			(start 0.67945 0.3048)
			(end 0.120396 0.3048)
			(stroke
				(width 0.1)
				(type default)
			)
			(layer "F.Fab")
		)
		(fp_line
			(start -0.12065 0.2794)
			(end -0.12065 0.3048)
			(stroke
				(width 0.1)
				(type default)
			)
			(layer "F.Fab")
		)
		(fp_line
			(start 0.120396 0.2794)
			(end -0.12065 0.2794)
			(stroke
				(width 0.1)
				(type default)
			)
			(layer "F.Fab")
		)
		(fp_line
			(start -0.12065 -0.2794)
			(end 0.12065 -0.2794)
			(stroke
				(width 0.1)
				(type default)
			)
			(layer "F.Fab")
		)
		(fp_line
			(start 0.12065 -0.2794)
			(end 0.12065 -0.3048)
			(stroke
				(width 0.1)
				(type default)
			)
			(layer "F.Fab")
		)
		(fp_line
			(start 0.12065 -0.3048)
			(end 0.67945 -0.3048)
			(stroke
				(width 0.1)
				(type default)
			)
			(layer "F.Fab")
		)
		(fp_line
			(start 0.67945 -0.3048)
			(end 0.67945 0.3048)
			(stroke
				(width 0.1)
				(type default)
			)
			(layer "F.Fab")
		)
		(fp_line
			(start -0.67945 -0.305054)
			(end -0.12065 -0.305054)
			(stroke
				(width 0.1)
				(type default)
			)
			(layer "F.Fab")
		)
		(fp_line
			(start -0.12065 -0.305054)
			(end -0.12065 -0.2794)
			(stroke
				(width 0.1)
				(type default)
			)
			(layer "F.Fab")
		)
		(pad "1" smd circle
			(at -0.40005 0 270)
			(size 0 0)
			(layers "F.Cu" "F.Mask" "F.Paste")
			(net "SPI_BMC_BT_WP0_N_R")
		)
		(pad "2" smd circle
			(at 0.40005 0 270)
			(size 0 0)
			(layers "F.Cu" "F.Mask" "F.Paste")
			(net "GND")
		)
	)
)
